# S9S_MB_2U (Grand Teton) — schematic netlist excerpt (pin names and nets, part order shuffled) for the footprints in the layout excerpt that follows; sources: Cadence DE-HDL packaged netlist, KiCad conversion of 03242023_DA0F0TMBIJ0_F0T_Motherboard_J_brd_V01_OCP.brd

C994  Q_CAP  10UF 6.3V 20% X6S  pkg C0402  page 74 : A = PVCCIN_CPU0 ; B = GND
C300  Q_CAP  22UF 4V 20% X6S  pkg C0402  page 77 : A = PVCCIN_CPU1 ; B = GND

(kicad_pcb
	(version 20260206)
	(generator "pcbnew")
	(generator_version "10.0")
	(general
		(thickness 1.6)
		(legacy_teardrops no)
	)
	(paper "A4")
	(title_block
		(title "03242023_DA0F0TMBIJ0_F0T_Motherboard_J_brd_V01_OCP.brd")
		(comment 1 "Grand Teton / footprints 2175-2176 of 6105")
	)
	(layers
		(0 "F.Cu" signal "TOP")
		(4 "In1.Cu" signal "GND")
		(6 "In2.Cu" signal "IN1")
		(8 "In3.Cu" signal "GND1")
		(10 "In4.Cu" signal "IN2")
		(12 "In5.Cu" signal "GND2")
		(14 "In6.Cu" signal "IN3")
		(16 "In7.Cu" signal "GND3")
		(18 "In8.Cu" signal "VCC")
		(20 "In9.Cu" signal "VCC1")
		(22 "In10.Cu" signal "GND4")
		(24 "In11.Cu" signal "IN4")
		(26 "In12.Cu" signal "GND5")
		(28 "In13.Cu" signal "IN5")
		(30 "In14.Cu" signal "GND6")
		(32 "In15.Cu" signal "IN6")
		(34 "In16.Cu" signal "GND7")
		(2 "B.Cu" signal "BOTTOM")
		(9 "F.Adhes" user "F.Adhesive")
		(11 "B.Adhes" user "B.Adhesive")
		(13 "F.Paste" user "Package Geometry/Pastemask Top")
		(15 "B.Paste" user "Package Geometry/Pastemask Bottom")
		(5 "F.SilkS" user "Ref Des/Silkscreen Top")
		(7 "B.SilkS" user "Ref Des/Silkscreen Bottom")
		(1 "F.Mask" user "Board Geometry/Soldermask Top")
		(3 "B.Mask" user "Board Geometry/Soldermask Bottom")
		(17 "Dwgs.User" user "User.Drawings")
		(19 "Cmts.User" user "User.Comments")
		(21 "Eco1.User" user "User.Eco1")
		(23 "Eco2.User" user "User.Eco2")
		(25 "Edge.Cuts" user "Board Geometry/Outline")
		(27 "Margin" user)
		(31 "F.CrtYd" user "Package Geometry/Place Bound Top")
		(29 "B.CrtYd" user "Package Geometry/Place Bound Bottom")
		(35 "F.Fab" user "Ref Des/Assembly Top")
		(33 "B.Fab" user "Ref Des/Assembly Bottom")
	)
	(footprint ""
		(layer "F.Cu")
		(at 355.216714 -255.053846 90)
		(property "Reference" "C994"
			(at 0 0 90)
			(layer "F.SilkS")
			(hide yes)
			(effects
				(font
					(size 1.27 1.27)
				)
			)
		)
		(property "Value" ""
			(at 0 0 90)
			(layer "F.Fab")
			(effects
				(font
					(size 1.27 1.27)
				)
			)
		)
		(duplicate_pad_numbers_are_jumpers no)
		(fp_line
			(start 0.7874 -0.4064)
			(end 0.7874 0.4064)
			(stroke
				(width 0.1524)
				(type default)
			)
			(layer "F.SilkS")
		)
		(fp_line
			(start -0.7874 -0.4064)
			(end 0.7874 -0.4064)
			(stroke
				(width 0.1524)
				(type default)
			)
			(layer "F.SilkS")
		)
		(fp_line
			(start 0.7874 0.4064)
			(end -0.7874 0.4064)
			(stroke
				(width 0.1524)
				(type default)
			)
			(layer "F.SilkS")
		)
		(fp_line
			(start -0.7874 0.4064)
			(end -0.7874 -0.4064)
			(stroke
				(width 0.1524)
				(type default)
			)
			(layer "F.SilkS")
		)
		(fp_line
			(start -0.12065 -0.305054)
			(end -0.12065 -0.2794)
			(stroke
				(width 0.1)
				(type default)
			)
			(layer "F.Fab")
		)
		(fp_line
			(start -0.67945 -0.305054)
			(end -0.12065 -0.305054)
			(stroke
				(width 0.1)
				(type default)
			)
			(layer "F.Fab")
		)
		(fp_line
			(start 0.67945 -0.3048)
			(end 0.67945 0.3048)
			(stroke
				(width 0.1)
				(type default)
			)
			(layer "F.Fab")
		)
		(fp_line
			(start 0.12065 -0.3048)
			(end 0.67945 -0.3048)
			(stroke
				(width 0.1)
				(type default)
			)
			(layer "F.Fab")
		)
		(fp_line
			(start 0.12065 -0.2794)
			(end 0.12065 -0.3048)
			(stroke
				(width 0.1)
				(type default)
			)
			(layer "F.Fab")
		)
		(fp_line
			(start -0.12065 -0.2794)
			(end 0.12065 -0.2794)
			(stroke
				(width 0.1)
				(type default)
			)
			(layer "F.Fab")
		)
		(fp_line
			(start 0.120396 0.2794)
			(end -0.12065 0.2794)
			(stroke
				(width 0.1)
				(type default)
			)
			(layer "F.Fab")
		)
		(fp_line
			(start -0.12065 0.2794)
			(end -0.12065 0.3048)
			(stroke
				(width 0.1)
				(type default)
			)
			(layer "F.Fab")
		)
		(fp_line
			(start 0.67945 0.3048)
			(end 0.120396 0.3048)
			(stroke
				(width 0.1)
				(type default)
			)
			(layer "F.Fab")
		)
		(fp_line
			(start 0.120396 0.3048)
			(end 0.120396 0.2794)
			(stroke
				(width 0.1)
				(type default)
			)
			(layer "F.Fab")
		)
		(fp_line
			(start -0.12065 0.3048)
			(end -0.67945 0.3048)
			(stroke
				(width 0.1)
				(type default)
			)
			(layer "F.Fab")
		)
		(fp_line
			(start -0.67945 0.3048)
			(end -0.67945 -0.305054)
			(stroke
				(width 0.1)
				(type default)
			)
			(layer "F.Fab")
		)
		(pad "1" smd circle
			(at -0.40005 0 90)
			(size 0 0)
			(layers "F.Cu" "F.Mask" "F.Paste")
			(net "PVCCIN_CPU0")
		)
		(pad "2" smd circle
			(at 0.40005 0 90)
			(size 0 0)
			(layers "F.Cu" "F.Mask" "F.Paste")
			(net "GND")
		)
	)
	(footprint ""
		(layer "F.Cu")
		(at 106.331004 -244.032024 90)
		(property "Reference" "C300"
			(at 0 0 90)
			(layer "F.SilkS")
			(hide yes)
			(effects
				(font
					(size 1.27 1.27)
				)
			)
		)
		(property "Value" ""
			(at 0 0 90)
			(layer "F.Fab")
			(effects
				(font
					(size 1.27 1.27)
				)
			)
		)
		(duplicate_pad_numbers_are_jumpers no)
		(fp_line
			(start 0.7874 -0.4064)
			(end 0.7874 0.4064)
			(stroke
				(width 0.1524)
				(type default)
			)
			(layer "F.SilkS")
		)
		(fp_line
			(start -0.7874 -0.4064)
			(end 0.7874 -0.4064)
			(stroke
				(width 0.1524)
				(type default)
			)
			(layer "F.SilkS")
		)
		(fp_line
			(start 0.7874 0.4064)
			(end -0.7874 0.4064)
			(stroke
				(width 0.1524)
				(type default)
			)
			(layer "F.SilkS")
		)
		(fp_line
			(start -0.7874 0.4064)
			(end -0.7874 -0.4064)
			(stroke
				(width 0.1524)
				(type default)
			)
			(layer "F.SilkS")
		)
		(fp_line
			(start -0.12065 -0.305054)
			(end -0.12065 -0.2794)
			(stroke
				(width 0.1)
				(type default)
			)
			(layer "F.Fab")
		)
		(fp_line
			(start -0.67945 -0.305054)
			(end -0.12065 -0.305054)
			(stroke
				(width 0.1)
				(type default)
			)
			(layer "F.Fab")
		)
		(fp_line
			(start 0.67945 -0.3048)
			(end 0.67945 0.3048)
			(stroke
				(width 0.1)
				(type default)
			)
			(layer "F.Fab")
		)
		(fp_line
			(start 0.12065 -0.3048)
			(end 0.67945 -0.3048)
			(stroke
				(width 0.1)
				(type default)
			)
			(layer "F.Fab")
		)
		(fp_line
			(start 0.12065 -0.2794)
			(end 0.12065 -0.3048)
			(stroke
				(width 0.1)
				(type default)
			)
			(layer "F.Fab")
		)
		(fp_line
			(start -0.12065 -0.2794)
			(end 0.12065 -0.2794)
			(stroke
				(width 0.1)
				(type default)
			)
			(layer "F.Fab")
		)
		(fp_line
			(start 0.120396 0.2794)
			(end -0.12065 0.2794)
			(stroke
				(width 0.1)
				(type default)
			)
			(layer "F.Fab")
		)
		(fp_line
			(start -0.12065 0.2794)
			(end -0.12065 0.3048)
			(stroke
				(width 0.1)
				(type default)
			)
			(layer "F.Fab")
		)
		(fp_line
			(start 0.67945 0.3048)
			(end 0.120396 0.3048)
			(stroke
				(width 0.1)
				(type default)
			)
			(layer "F.Fab")
		)
		(fp_line
			(start 0.120396 0.3048)
			(end 0.120396 0.2794)
			(stroke
				(width 0.1)
				(type default)
			)
			(layer "F.Fab")
		)
		(fp_line
			(start -0.12065 0.3048)
			(end -0.67945 0.3048)
			(stroke
				(width 0.1)
				(type default)
			)
			(layer "F.Fab")
		)
		(fp_line
			(start -0.67945 0.3048)
			(end -0.67945 -0.305054)
			(stroke
				(width 0.1)
				(type default)
			)
			(layer "F.Fab")
		)
		(pad "1" smd circle
			(at -0.40005 0 90)
			(size 0 0)
			(layers "F.Cu" "F.Mask" "F.Paste")
			(net "PVCCIN_CPU1")
		)
		(pad "2" smd circle
			(at 0.40005 0 90)
			(size 0 0)
			(layers "F.Cu" "F.Mask" "F.Paste")
			(net "GND")
		)
	)
)
